# T6G (Grand Teton) — schematic netlist excerpt (pin names and nets, part order shuffled) for the footprints in the layout excerpt that follows; sources: Cadence DE-HDL packaged netlist, KiCad conversion of 04192023_DAF0TMB3IC0_F0TG_MB_C_brd_V02_OCP.brd

PR114  Q_RES  49.9 1% CHIP  pkg 0402LF  page 207 : A = PVDD11_S3_P0 ; B = VSENSE_PVDD11_S3_P0_DP
PR365  Q_RES  8.87K 1% EMPTY  pkg 0402LF  page 199 : A = GND ; B = PVDDCR_SOC_P0_LSET3

(kicad_pcb
	(version 20260206)
	(generator "pcbnew")
	(generator_version "10.0")
	(general
		(thickness 1.6)
		(legacy_teardrops no)
	)
	(paper "A4")
	(title_block
		(title "04192023_DAF0TMB3IC0_F0TG_MB_C_brd_V02_OCP.brd")
		(comment 1 "Grand Teton / footprints 2322-2323 of 8354")
	)
	(layers
		(0 "F.Cu" signal "TOP")
		(4 "In1.Cu" signal "GND")
		(6 "In2.Cu" signal "IN1")
		(8 "In3.Cu" signal "GND1")
		(10 "In4.Cu" signal "IN2")
		(12 "In5.Cu" signal "GND2")
		(14 "In6.Cu" signal "IN3")
		(16 "In7.Cu" signal "GND3")
		(18 "In8.Cu" signal "VCC")
		(20 "In9.Cu" signal "VCC1")
		(22 "In10.Cu" signal "GND4")
		(24 "In11.Cu" signal "IN4")
		(26 "In12.Cu" signal "GND5")
		(28 "In13.Cu" signal "IN5")
		(30 "In14.Cu" signal "GND6")
		(32 "In15.Cu" signal "IN6")
		(34 "In16.Cu" signal "GND7")
		(2 "B.Cu" signal "BOTTOM")
		(9 "F.Adhes" user "F.Adhesive")
		(11 "B.Adhes" user "B.Adhesive")
		(13 "F.Paste" user "Package Geometry/Pastemask Top")
		(15 "B.Paste" user "Package Geometry/Pastemask Bottom")
		(5 "F.SilkS" user "Ref Des/Silkscreen Top")
		(7 "B.SilkS" user "Ref Des/Silkscreen Bottom")
		(1 "F.Mask" user "Board Geometry/Soldermask Top")
		(3 "B.Mask" user "Board Geometry/Soldermask Bottom")
		(17 "Dwgs.User" user "User.Drawings")
		(19 "Cmts.User" user "User.Comments")
		(21 "Eco1.User" user "User.Eco1")
		(23 "Eco2.User" user "User.Eco2")
		(25 "Edge.Cuts" user "Board Geometry/Outline")
		(27 "Margin" user)
		(31 "F.CrtYd" user "Package Geometry/Place Bound Top")
		(29 "B.CrtYd" user "Package Geometry/Place Bound Bottom")
		(35 "F.Fab" user "Ref Des/Assembly Top")
		(33 "B.Fab" user "Ref Des/Assembly Bottom")
	)
	(footprint ""
		(layer "F.Cu")
		(at 415.628582 -333.215996 180)
		(property "Reference" "PR114"
			(at 0 0 180)
			(layer "F.SilkS")
			(hide yes)
			(effects
				(font
					(size 1.27 1.27)
				)
			)
		)
		(property "Value" ""
			(at 0 0 180)
			(layer "F.Fab")
			(effects
				(font
					(size 1.27 1.27)
				)
			)
		)
		(duplicate_pad_numbers_are_jumpers no)
		(fp_line
			(start 0.7874 0.4064)
			(end -0.7874 0.4064)
			(stroke
				(width 0.1524)
				(type default)
			)
			(layer "F.SilkS")
		)
		(fp_line
			(start 0.7874 -0.4064)
			(end 0.7874 0.4064)
			(stroke
				(width 0.1524)
				(type default)
			)
			(layer "F.SilkS")
		)
		(fp_line
			(start -0.7874 0.4064)
			(end -0.7874 -0.4064)
			(stroke
				(width 0.1524)
				(type default)
			)
			(layer "F.SilkS")
		)
		(fp_line
			(start -0.7874 -0.4064)
			(end 0.7874 -0.4064)
			(stroke
				(width 0.1524)
				(type default)
			)
			(layer "F.SilkS")
		)
		(fp_line
			(start 0.67945 0.3048)
			(end 0.120396 0.3048)
			(stroke
				(width 0.1)
				(type default)
			)
			(layer "F.Fab")
		)
		(fp_line
			(start 0.67945 -0.3048)
			(end 0.67945 0.3048)
			(stroke
				(width 0.1)
				(type default)
			)
			(layer "F.Fab")
		)
		(fp_line
			(start 0.12065 -0.2794)
			(end 0.12065 -0.3048)
			(stroke
				(width 0.1)
				(type default)
			)
			(layer "F.Fab")
		)
		(fp_line
			(start 0.12065 -0.3048)
			(end 0.67945 -0.3048)
			(stroke
				(width 0.1)
				(type default)
			)
			(layer "F.Fab")
		)
		(fp_line
			(start 0.120396 0.3048)
			(end 0.120396 0.2794)
			(stroke
				(width 0.1)
				(type default)
			)
			(layer "F.Fab")
		)
		(fp_line
			(start 0.120396 0.2794)
			(end -0.12065 0.2794)
			(stroke
				(width 0.1)
				(type default)
			)
			(layer "F.Fab")
		)
		(fp_line
			(start -0.12065 0.3048)
			(end -0.67945 0.3048)
			(stroke
				(width 0.1)
				(type default)
			)
			(layer "F.Fab")
		)
		(fp_line
			(start -0.12065 0.2794)
			(end -0.12065 0.3048)
			(stroke
				(width 0.1)
				(type default)
			)
			(layer "F.Fab")
		)
		(fp_line
			(start -0.12065 -0.2794)
			(end 0.12065 -0.2794)
			(stroke
				(width 0.1)
				(type default)
			)
			(layer "F.Fab")
		)
		(fp_line
			(start -0.12065 -0.305054)
			(end -0.12065 -0.2794)
			(stroke
				(width 0.1)
				(type default)
			)
			(layer "F.Fab")
		)
		(fp_line
			(start -0.67945 0.3048)
			(end -0.67945 -0.305054)
			(stroke
				(width 0.1)
				(type default)
			)
			(layer "F.Fab")
		)
		(fp_line
			(start -0.67945 -0.305054)
			(end -0.12065 -0.305054)
			(stroke
				(width 0.1)
				(type default)
			)
			(layer "F.Fab")
		)
		(pad "1" smd circle
			(at -0.40005 0 180)
			(size 0 0)
			(layers "F.Cu" "F.Mask" "F.Paste")
			(net "PVDD11_S3_P0")
		)
		(pad "2" smd circle
			(at 0.40005 0 180)
			(size 0 0)
			(layers "F.Cu" "F.Mask" "F.Paste")
			(net "VSENSE_PVDD11_S3_P0_DP")
		)
	)
	(footprint ""
		(layer "F.Cu")
		(at 415.834322 -158.556198)
		(property "Reference" "PR365"
			(at 0 0 0)
			(layer "F.SilkS")
			(hide yes)
			(effects
				(font
					(size 1.27 1.27)
				)
			)
		)
		(property "Value" ""
			(at 0 0 0)
			(layer "F.Fab")
			(effects
				(font
					(size 1.27 1.27)
				)
			)
		)
		(duplicate_pad_numbers_are_jumpers no)
		(fp_line
			(start -0.7874 -0.4064)
			(end 0.7874 -0.4064)
			(stroke
				(width 0.1524)
				(type default)
			)
			(layer "F.SilkS")
		)
		(fp_line
			(start -0.7874 0.4064)
			(end -0.7874 -0.4064)
			(stroke
				(width 0.1524)
				(type default)
			)
			(layer "F.SilkS")
		)
		(fp_line
			(start 0.7874 -0.4064)
			(end 0.7874 0.4064)
			(stroke
				(width 0.1524)
				(type default)
			)
			(layer "F.SilkS")
		)
		(fp_line
			(start 0.7874 0.4064)
			(end -0.7874 0.4064)
			(stroke
				(width 0.1524)
				(type default)
			)
			(layer "F.SilkS")
		)
		(fp_line
			(start -0.67945 -0.305054)
			(end -0.12065 -0.305054)
			(stroke
				(width 0.1)
				(type default)
			)
			(layer "F.Fab")
		)
		(fp_line
			(start -0.67945 0.3048)
			(end -0.67945 -0.305054)
			(stroke
				(width 0.1)
				(type default)
			)
			(layer "F.Fab")
		)
		(fp_line
			(start -0.12065 -0.305054)
			(end -0.12065 -0.2794)
			(stroke
				(width 0.1)
				(type default)
			)
			(layer "F.Fab")
		)
		(fp_line
			(start -0.12065 -0.2794)
			(end 0.12065 -0.2794)
			(stroke
				(width 0.1)
				(type default)
			)
			(layer "F.Fab")
		)
		(fp_line
			(start -0.12065 0.2794)
			(end -0.12065 0.3048)
			(stroke
				(width 0.1)
				(type default)
			)
			(layer "F.Fab")
		)
		(fp_line
			(start -0.12065 0.3048)
			(end -0.67945 0.3048)
			(stroke
				(width 0.1)
				(type default)
			)
			(layer "F.Fab")
		)
		(fp_line
			(start 0.120396 0.2794)
			(end -0.12065 0.2794)
			(stroke
				(width 0.1)
				(type default)
			)
			(layer "F.Fab")
		)
		(fp_line
			(start 0.120396 0.3048)
			(end 0.120396 0.2794)
			(stroke
				(width 0.1)
				(type default)
			)
			(layer "F.Fab")
		)
		(fp_line
			(start 0.12065 -0.3048)
			(end 0.67945 -0.3048)
			(stroke
				(width 0.1)
				(type default)
			)
			(layer "F.Fab")
		)
		(fp_line
			(start 0.12065 -0.2794)
			(end 0.12065 -0.3048)
			(stroke
				(width 0.1)
				(type default)
			)
			(layer "F.Fab")
		)
		(fp_line
			(start 0.67945 -0.3048)
			(end 0.67945 0.3048)
			(stroke
				(width 0.1)
				(type default)
			)
			(layer "F.Fab")
		)
		(fp_line
			(start 0.67945 0.3048)
			(end 0.120396 0.3048)
			(stroke
				(width 0.1)
				(type default)
			)
			(layer "F.Fab")
		)
		(pad "1" smd circle
			(at -0.40005 0)
			(size 0 0)
			(layers "F.Cu" "F.Mask" "F.Paste")
			(net "GND")
		)
		(pad "2" smd circle
			(at 0.40005 0)
			(size 0 0)
			(layers "F.Cu" "F.Mask" "F.Paste")
			(net "PVDDCR_SOC_P0_LSET3")
		)
	)
)
